# TIMECARD (Time Appliance Project (Time Card)) — schematic netlist excerpt (pin names and nets, part order shuffled) for the footprints in the layout excerpt that follows; sources: Cadence DE-HDL packaged netlist, KiCad conversion of R4006-B0001-02_R01.brd

C244  CAPACITOR  0.1UF 25V 10%  pkg SMC_0402R_H022  page 15 : \1\ = XP3R3V ; \2\ = SG
R150  RESISTOR  4.7KOHM 1%  pkg SMC_0402R_H016  page 16 : \1\ = XP3R3V_FPGA ; \2\ = UNNAMED_5_PCA9546APWTSSOP16_I_1

(kicad_pcb
	(version 20260206)
	(generator "pcbnew")
	(generator_version "10.0")
	(general
		(thickness 1.6)
		(legacy_teardrops no)
	)
	(paper "A4")
	(title_block
		(title "timecard-production-celestica-r4006 — R4006-B0001-02_R01.brd")
		(comment 1 "Time Appliance Project (Time Card) / footprints 1039-1040 of 1113")
	)
	(layers
		(0 "F.Cu" signal "TOP")
		(4 "In1.Cu" signal "L02_GND1")
		(6 "In2.Cu" signal "L03_SIG1")
		(8 "In3.Cu" signal "L04_GND2")
		(10 "In4.Cu" signal "L05_VCC1")
		(12 "In5.Cu" signal "L06_VCC2")
		(14 "In6.Cu" signal "L07_GND3")
		(16 "In7.Cu" signal "L08_SIG2")
		(18 "In8.Cu" signal "L09_GND4")
		(2 "B.Cu" signal "BOTTOM")
		(9 "F.Adhes" user "F.Adhesive")
		(11 "B.Adhes" user "B.Adhesive")
		(13 "F.Paste" user "Package Geometry/Pastemask Top")
		(15 "B.Paste" user "Package Geometry/Pastemask Bottom")
		(5 "F.SilkS" user "Ref Des/Silkscreen Top")
		(7 "B.SilkS" user "Ref Des/Silkscreen Bottom")
		(1 "F.Mask" user "Board Geometry/Soldermask Top")
		(3 "B.Mask" user "Board Geometry/Soldermask Bottom")
		(17 "Dwgs.User" user "User.Drawings")
		(19 "Cmts.User" user "User.Comments")
		(21 "Eco1.User" user "User.Eco1")
		(23 "Eco2.User" user "User.Eco2")
		(25 "Edge.Cuts" user "Board Geometry/Outline")
		(27 "Margin" user)
		(31 "F.CrtYd" user "Package Geometry/Place Bound Top")
		(29 "B.CrtYd" user "Package Geometry/Place Bound Bottom")
		(35 "F.Fab" user "Ref Des/Assembly Top")
		(33 "B.Fab" user "Ref Des/Assembly Bottom")
	)
	(footprint ""
		(layer "B.Cu")
		(at 83.2358 -84.836 180)
		(property "Reference" "R150"
			(at 0.6858 5.67563 0)
			(unlocked yes)
			(layer "B.SilkS")
			(effects
				(font
					(size 0.7874 0.5842)
					(thickness 0.1524)
				)
				(justify mirror)
			)
		)
		(property "Value" "VAL*"
			(at -0.02032 2.13233 180)
			(unlocked yes)
			(layer "B.Fab")
			(hide yes)
			(effects
				(font
					(size 0.7874 0.5842)
					(thickness 0.1524)
				)
				(justify mirror)
			)
		)
		(property "Tolerance" "TOL*"
			(at -0.044704 3.05435 180)
			(unlocked yes)
			(layer "Cmts.User")
			(hide yes)
			(effects
				(font
					(size 0.7874 0.5842)
					(thickness 0.1524)
				)
				(justify mirror)
			)
		)
		(property "User Part Number" "PARTNUM*"
			(at -0.02032 4.024884 180)
			(unlocked yes)
			(layer "Cmts.User")
			(hide yes)
			(effects
				(font
					(size 0.7874 0.5842)
					(thickness 0.1524)
				)
				(justify mirror)
			)
		)
		(property "Device Type" "RESISTOR-G155-14701-01,4.7KOHMA"
			(at -0.008382 1.210564 180)
			(unlocked yes)
			(layer "B.Fab")
			(hide yes)
			(effects
				(font
					(size 0.7874 0.5842)
					(thickness 0.1524)
				)
				(justify mirror)
			)
		)
		(duplicate_pad_numbers_are_jumpers no)
		(fp_line
			(start 1.143 0.5588)
			(end -1.143 0.5588)
			(stroke
				(width 0.1)
				(type default)
			)
			(layer "B.SilkS")
		)
		(fp_line
			(start 1.143 -0.5588)
			(end 1.143 0.5588)
			(stroke
				(width 0.1)
				(type default)
			)
			(layer "B.SilkS")
		)
		(fp_line
			(start -1.143 0.5588)
			(end -1.143 -0.5588)
			(stroke
				(width 0.1)
				(type default)
			)
			(layer "B.SilkS")
		)
		(fp_line
			(start -1.143 -0.5588)
			(end 1.143 -0.5588)
			(stroke
				(width 0.1)
				(type default)
			)
			(layer "B.SilkS")
		)
		(fp_rect
			(start -1.143 0.5588)
			(end 1.143 -0.5588)
			(stroke
				(width 0)
				(type default)
			)
			(fill no)
			(layer "B.CrtYd")
		)
		(fp_line
			(start 0.508 0.3048)
			(end -0.508 0.3048)
			(stroke
				(width 0.1)
				(type default)
			)
			(layer "B.Fab")
		)
		(fp_line
			(start 0.508 -0.3048)
			(end 0.508 0.3048)
			(stroke
				(width 0.1)
				(type default)
			)
			(layer "B.Fab")
		)
		(fp_line
			(start -0.508 0.3048)
			(end -0.508 -0.3048)
			(stroke
				(width 0.1)
				(type default)
			)
			(layer "B.Fab")
		)
		(fp_line
			(start -0.508 -0.3048)
			(end 0.508 -0.3048)
			(stroke
				(width 0.1)
				(type default)
			)
			(layer "B.Fab")
		)
		(pad "1" smd rect
			(at 0.5334 0)
			(size 0.7112 0.6096)
			(layers "B.Cu" "B.Mask" "B.Paste")
			(net "XP3R3V_FPGA")
		)
		(pad "2" smd rect
			(at -0.5334 0)
			(size 0.7112 0.6096)
			(layers "B.Cu" "B.Mask" "B.Paste")
			(net "UNNAMED_5_PCA9546APWTSSOP16_I_1")
		)
		(zone
			(layer "B.Cu")
			(hatch none 0.5)
			(connect_pads
				(clearance 0)
			)
			(min_thickness 0.25)
			(keepout
				(tracks allowed)
				(vias not_allowed)
				(pads allowed)
				(copperpour not_allowed)
				(footprints allowed)
			)
			(placement
				(enabled no)
				(sheetname "")
			)
			(fill
				(thermal_gap 0.5)
				(thermal_bridge_width 0.5)
				(island_removal_mode 0)
			)
			(polygon
				(pts
					(xy 83.312 -85.1408) (xy 83.1596 -85.1408) (xy 83.1596 -84.5312) (xy 83.312 -84.5312)
				)
			)
		)
	)
	(footprint ""
		(layer "B.Cu")
		(at 108.966 -18.542 180)
		(property "Reference" "C244"
			(at 0 -1.30937 0)
			(unlocked yes)
			(layer "B.SilkS")
			(effects
				(font
					(size 0.7874 0.5842)
					(thickness 0.1524)
				)
				(justify mirror)
			)
		)
		(property "Value" "VAL*"
			(at -0.0762 2.067306 180)
			(unlocked yes)
			(layer "B.Fab")
			(hide yes)
			(effects
				(font
					(size 0.7874 0.5842)
					(thickness 0.1524)
				)
				(justify mirror)
			)
		)
		(property "Device Type" "CAPACITOR-G105-0B104-EK,0.1UF,A"
			(at -0.0508 1.127506 180)
			(unlocked yes)
			(layer "B.Fab")
			(hide yes)
			(effects
				(font
					(size 0.7874 0.5842)
					(thickness 0.1524)
				)
				(justify mirror)
			)
		)
		(property "User Part Number" "PARTNUM*"
			(at -0.1016 4.023106 180)
			(unlocked yes)
			(layer "Cmts.User")
			(hide yes)
			(effects
				(font
					(size 0.7874 0.5842)
					(thickness 0.1524)
				)
				(justify mirror)
			)
		)
		(property "Tolerance" "TOL*"
			(at -0.0762 3.032506 180)
			(unlocked yes)
			(layer "Cmts.User")
			(hide yes)
			(effects
				(font
					(size 0.7874 0.5842)
					(thickness 0.1524)
				)
				(justify mirror)
			)
		)
		(duplicate_pad_numbers_are_jumpers no)
		(fp_line
			(start 1.143 0.5588)
			(end -1.143 0.5588)
			(stroke
				(width 0.1)
				(type default)
			)
			(layer "B.SilkS")
		)
		(fp_line
			(start 1.143 -0.5588)
			(end 1.143 0.5588)
			(stroke
				(width 0.1)
				(type default)
			)
			(layer "B.SilkS")
		)
		(fp_line
			(start -1.143 0.5588)
			(end -1.143 -0.5588)
			(stroke
				(width 0.1)
				(type default)
			)
			(layer "B.SilkS")
		)
		(fp_line
			(start -1.143 -0.5588)
			(end 1.143 -0.5588)
			(stroke
				(width 0.1)
				(type default)
			)
			(layer "B.SilkS")
		)
		(fp_rect
			(start 1.143 -0.5588)
			(end -1.143 0.5588)
			(stroke
				(width 0)
				(type default)
			)
			(fill no)
			(layer "B.CrtYd")
		)
		(fp_line
			(start 0.508 0.3048)
			(end -0.508 0.3048)
			(stroke
				(width 0.1)
				(type default)
			)
			(layer "B.Fab")
		)
		(fp_line
			(start 0.508 -0.3048)
			(end 0.508 0.3048)
			(stroke
				(width 0.1)
				(type default)
			)
			(layer "B.Fab")
		)
		(fp_line
			(start -0.508 0.3048)
			(end -0.508 -0.3048)
			(stroke
				(width 0.1)
				(type default)
			)
			(layer "B.Fab")
		)
		(fp_line
			(start -0.508 -0.3048)
			(end 0.508 -0.3048)
			(stroke
				(width 0.1)
				(type default)
			)
			(layer "B.Fab")
		)
		(pad "1" smd rect
			(at 0.5334 0)
			(size 0.7112 0.6096)
			(layers "B.Cu" "B.Mask" "B.Paste")
			(net "XP3R3V")
		)
		(pad "2" smd rect
			(at -0.5334 0)
			(size 0.7112 0.6096)
			(layers "B.Cu" "B.Mask" "B.Paste")
			(net "SG")
		)
		(zone
			(layer "B.Cu")
			(hatch none 0.5)
			(connect_pads
				(clearance 0)
			)
			(min_thickness 0.25)
			(keepout
				(tracks allowed)
				(vias not_allowed)
				(pads allowed)
				(copperpour not_allowed)
				(footprints allowed)
			)
			(placement
				(enabled no)
				(sheetname "")
			)
			(fill
				(thermal_gap 0.5)
				(thermal_bridge_width 0.5)
				(island_removal_mode 0)
			)
			(polygon
				(pts
					(xy 108.8898 -18.2372) (xy 109.0422 -18.2372) (xy 109.0422 -18.8468) (xy 108.8898 -18.8468)
				)
			)
		)
	)
)
